# ddr5-testbed — KiCad project settings (.kicad_pro: net classes, design rules, text variables)
{
  "board": {
    "3dviewports": [],
    "design_settings": {
      "defaults": {
        "apply_defaults_to_fp_fields": false,
        "apply_defaults_to_fp_shapes": false,
        "apply_defaults_to_fp_text": false,
        "board_outline_line_width": 0.05,
        "copper_line_width": 0.2,
        "copper_text_italic": false,
        "copper_text_size_h": 1.5,
        "copper_text_size_v": 1.5,
        "copper_text_thickness": 0.3,
        "copper_text_upright": false,
        "courtyard_line_width": 0.05,
        "dimension_precision": 4,
        "dimension_units": 3,
        "dimensions": {
          "arrow_length": 1270000,
          "extension_offset": 500000,
          "keep_text_aligned": true,
          "suppress_zeroes": false,
          "text_position": 0,
          "units_format": 1
        },
        "fab_line_width": 0.1,
        "fab_text_italic": false,
        "fab_text_size_h": 1.0,
        "fab_text_size_v": 1.0,
        "fab_text_thickness": 0.15,
        "fab_text_upright": false,
        "other_line_width": 0.1,
        "other_text_italic": false,
        "other_text_size_h": 1.0,
        "other_text_size_v": 1.0,
        "other_text_thickness": 0.15,
        "other_text_upright": false,
        "pads": {
          "drill": 0.762,
          "height": 1.524,
          "width": 1.524
        },
        "silk_line_width": 0.12,
        "silk_text_italic": false,
        "silk_text_size_h": 1.0,
        "silk_text_size_v": 1.0,
        "silk_text_thickness": 0.15,
        "silk_text_upright": false,
        "zones": {
          "45_degree_only": false,
          "min_clearance": 0.508
        }
      },
      "diff_pair_dimensions": [
        {
          "gap": 0.0,
          "via_gap": 0.0,
          "width": 0.0
        }
      ],
      "drc_exclusions": [],
      "meta": {
        "version": 2
      },
      "rule_severities": {
        "annular_width": "error",
        "clearance": "error",
        "connection_width": "warning",
        "copper_edge_clearance": "ignore",
        "copper_sliver": "warning",
        "courtyards_overlap": "error",
        "creepage": "error",
        "diff_pair_gap_out_of_range": "error",
        "diff_pair_uncoupled_length_too_long": "error",
        "drill_out_of_range": "error",
        "duplicate_footprints": "warning",
        "extra_footprint": "warning",
        "footprint": "error",
        "footprint_filters_mismatch": "ignore",
        "footprint_symbol_mismatch": "warning",
        "footprint_type_mismatch": "error",
        "hole_clearance": "error",
        "hole_near_hole": "error",
        "hole_to_hole": "error",
        "holes_co_located": "warning",
        "invalid_outline": "error",
        "isolated_copper": "warning",
        "item_on_disabled_layer": "error",
        "items_not_allowed": "error",
        "length_out_of_range": "error",
        "lib_footprint_issues": "ignore",
        "lib_footprint_mismatch": "warning",
        "malformed_courtyard": "error",
        "microvia_drill_out_of_range": "error",
        "mirrored_text_on_front_layer": "warning",
        "missing_courtyard": "ignore",
        "missing_footprint": "warning",
        "net_conflict": "warning",
        "nonmirrored_text_on_back_layer": "warning",
        "npth_inside_courtyard": "ignore",
        "padstack": "error",
        "pth_inside_courtyard": "ignore",
        "shorting_items": "error",
        "silk_edge_clearance": "warning",
        "silk_over_copper": "ignore",
        "silk_overlap": "warning",
        "skew_out_of_range": "error",
        "solder_mask_bridge": "error",
        "starved_thermal": "error",
        "text_height": "warning",
        "text_on_edge_cuts": "error",
        "text_thickness": "warning",
        "through_hole_pad_without_hole": "error",
        "too_many_vias": "error",
        "track_angle": "error",
        "track_dangling": "warning",
        "track_segment_length": "error",
        "track_width": "error",
        "tracks_crossing": "error",
        "unconnected_items": "error",
        "unresolved_variable": "error",
        "via_dangling": "warning",
        "zones_intersect": "error"
      },
      "rule_severitieslegacy_courtyards_overlap": true,
      "rule_severitieslegacy_no_courtyard_defined": false,
      "rules": {
        "allow_blind_buried_vias": true,
        "allow_microvias": false,
        "max_error": 0.005,
        "min_clearance": 0.1,
        "min_connection": 0.0,
        "min_copper_edge_clearance": 0.05,
        "min_groove_width": 0.0,
        "min_hole_clearance": 0.2,
        "min_hole_to_hole": 0.25,
        "min_microvia_diameter": 0.2,
        "min_microvia_drill": 0.1,
        "min_resolved_spokes": 2,
        "min_silk_clearance": 0.0,
        "min_text_height": 0.6,
        "min_text_thickness": 0.08,
        "min_through_hole_diameter": 0.15,
        "min_track_width": 0.1,
        "min_via_annular_width": 0.125,
        "min_via_diameter": 0.4,
        "solder_mask_clearance": 0.05,
        "solder_mask_min_width": 0.0,
        "solder_mask_to_copper_clearance": 0.0,
        "solder_paste_clearance": 0.0,
        "solder_paste_margin_ratio": -0.0,
        "use_height_for_length_calcs": true
      },
      "teardrop_options": [
        {
          "td_onpthpad": true,
          "td_onroundshapesonly": false,
          "td_onsmdpad": true,
          "td_ontrackend": false,
          "td_onvia": true
        }
      ],
      "teardrop_parameters": [
        {
          "td_allow_use_two_tracks": true,
          "td_curve_segcount": 1,
          "td_height_ratio": 1.0,
          "td_length_ratio": 0.5,
          "td_maxheight": 2.0,
          "td_maxlen": 1.0,
          "td_on_pad_in_zone": false,
          "td_target_name": "td_round_shape",
          "td_width_to_size_filter_ratio": 0.9
        },
        {
          "td_allow_use_two_tracks": true,
          "td_curve_segcount": 1,
          "td_height_ratio": 1.0,
          "td_length_ratio": 0.5,
          "td_maxheight": 2.0,
          "td_maxlen": 1.0,
          "td_on_pad_in_zone": false,
          "td_target_name": "td_rect_shape",
          "td_width_to_size_filter_ratio": 0.9
        },
        {
          "td_allow_use_two_tracks": true,
          "td_curve_segcount": 1,
          "td_height_ratio": 1.0,
          "td_length_ratio": 0.5,
          "td_maxheight": 2.0,
          "td_maxlen": 1.0,
          "td_on_pad_in_zone": false,
          "td_target_name": "td_track_end",
          "td_width_to_size_filter_ratio": 0.9
        }
      ],
      "track_widths": [
        0.0,
        0.1,
        0.1016,
        0.127,
        0.145,
        0.17,
        0.2
      ],
      "tuning_pattern_settings": {
        "diff_pair_defaults": {
          "corner_radius_percentage": 80,
          "corner_style": 1,
          "max_amplitude": 1.0,
          "min_amplitude": 0.2,
          "single_sided": false,
          "spacing": 1.0
        },
        "diff_pair_skew_defaults": {
          "corner_radius_percentage": 80,
          "corner_style": 1,
          "max_amplitude": 1.0,
          "min_amplitude": 0.2,
          "single_sided": false,
          "spacing": 0.6
        },
        "single_track_defaults": {
          "corner_radius_percentage": 80,
          "corner_style": 1,
          "max_amplitude": 1.0,
          "min_amplitude": 0.2,
          "single_sided": false,
          "spacing": 0.6
        }
      },
      "via_dimensions": [
        {
          "diameter": 0.0,
          "drill": 0.0
        },
        {
          "diameter": 0.4,
          "drill": 0.15
        },
        {
          "diameter": 0.45,
          "drill": 0.15
        },
        {
          "diameter": 0.5,
          "drill": 0.2
        }
      ],
      "zones_allow_external_fillets": false,
      "zones_use_no_outline": true
    },
    "ipc2581": {
      "dist": "",
      "distpn": "",
      "internal_id": "",
      "mfg": "",
      "mpn": ""
    },
    "layer_pairs": [],
    "layer_presets": [],
    "viewports": []
  },
  "boards": [],
  "cvpcb": {
    "equivalence_files": []
  },
  "erc": {
    "erc_exclusions": [],
    "meta": {
      "version": 0
    },
    "pin_map": [
      [
        0,
        0,
        0,
        0,
        0,
        0,
        1,
        0,
        0,
        0,
        0,
        2
      ],
      [
        0,
        2,
        0,
        1,
        0,
        0,
        1,
        0,
        2,
        2,
        2,
        2
      ],
      [
        0,
        0,
        0,
        0,
        0,
        0,
        1,
        0,
        1,
        0,
        1,
        2
      ],
      [
        0,
        1,
        0,
        0,
        0,
        0,
        1,
        1,
        2,
        1,
        1,
        2
      ],
      [
        0,
        0,
        0,
        0,
        0,
        0,
        1,
        0,
        0,
        0,
        0,
        2
      ],
      [
        0,
        0,
        0,
        0,
        0,
        0,
        0,
        0,
        0,
        0,
        0,
        2
      ],
      [
        1,
        1,
        1,
        1,
        1,
        0,
        1,
        1,
        1,
        1,
        1,
        2
      ],
      [
        0,
        0,
        0,
        1,
        0,
        0,
        1,
        0,
        0,
        0,
        0,
        2
      ],
      [
        0,
        2,
        1,
        2,
        0,
        0,
        1,
        0,
        2,
        2,
        2,
        2
      ],
      [
        0,
        2,
        0,
        1,
        0,
        0,
        1,
        0,
        2,
        0,
        0,
        2
      ],
      [
        0,
        2,
        1,
        1,
        0,
        0,
        1,
        0,
        2,
        0,
        0,
        2
      ],
      [
        2,
        2,
        2,
        2,
        2,
        2,
        2,
        2,
        2,
        2,
        2,
        2
      ]
    ],
    "rule_severities": {
      "bus_definition_conflict": "error",
      "bus_entry_needed": "error",
      "bus_to_bus_conflict": "error",
      "bus_to_net_conflict": "error",
      "conflicting_netclasses": "error",
      "different_unit_footprint": "error",
      "different_unit_net": "error",
      "duplicate_reference": "error",
      "duplicate_sheet_names": "error",
      "endpoint_off_grid": "warning",
      "extra_units": "error",
      "footprint_filter": "ignore",
      "footprint_link_issues": "warning",
      "four_way_junction": "ignore",
      "global_label_dangling": "warning",
      "hier_label_mismatch": "error",
      "label_dangling": "error",
      "label_multiple_wires": "warning",
      "lib_symbol_issues": "warning",
      "lib_symbol_mismatch": "warning",
      "missing_bidi_pin": "warning",
      "missing_input_pin": "warning",
      "missing_power_pin": "error",
      "missing_unit": "warning",
      "multiple_net_names": "warning",
      "net_not_bus_member": "warning",
      "no_connect_connected": "warning",
      "no_connect_dangling": "warning",
      "pin_not_connected": "error",
      "pin_not_driven": "error",
      "pin_to_pin": "warning",
      "power_pin_not_driven": "error",
      "same_local_global_label": "warning",
      "similar_label_and_power": "warning",
      "similar_labels": "warning",
      "similar_power": "warning",
      "simulation_model_issue": "ignore",
      "single_global_label": "ignore",
      "unannotated": "error",
      "unconnected_wire_endpoint": "warning",
      "undefined_netclass": "error",
      "unit_value_mismatch": "error",
      "unresolved_variable": "error",
      "wire_dangling": "error"
    }
  },
  "libraries": {
    "pinned_footprint_libs": [],
    "pinned_symbol_libs": []
  },
  "meta": {
    "filename": "ddr5-testbed.kicad_pro",
    "version": 3
  },
  "net_settings": {
    "classes": [
      {
        "bus_width": 12,
        "clearance": 0.1,
        "diff_pair_gap": 0.25,
        "diff_pair_via_gap": 0.25,
        "diff_pair_width": 0.2,
        "line_style": 0,
        "microvia_diameter": 0.3,
        "microvia_drill": 0.1,
        "name": "Default",
        "pcb_color": "rgba(0, 0, 0, 0.000)",
        "priority": 2147483647,
        "schematic_color": "rgba(0, 0, 0, 0.000)",
        "track_width": 0.12,
        "via_diameter": 0.45,
        "via_drill": 0.15,
        "wire_width": 6
      }
    ],
    "meta": {
      "version": 4
    },
    "net_colors": null,
    "netclass_assignments": null,
    "netclass_patterns": []
  },
  "pcbnew": {
    "last_paths": {
      "gencad": "",
      "idf": "",
      "netlist": "",
      "plot": "",
      "pos_files": "",
      "specctra_dsn": "",
      "step": "",
      "svg": "",
      "vrml": ""
    },
    "page_layout_descr_file": ""
  },
  "schematic": {
    "annotate_start_num": 0,
    "bom_export_filename": "${PROJECTNAME}.csv",
    "bom_fmt_presets": [],
    "bom_fmt_settings": {
      "field_delimiter": ",",
      "keep_line_breaks": false,
      "keep_tabs": false,
      "name": "CSV",
      "ref_delimiter": ",",
      "ref_range_delimiter": "",
      "string_delimiter": "\""
    },
    "bom_presets": [],
    "bom_settings": {
      "exclude_dnp": false,
      "fields_ordered": [
        {
          "group_by": false,
          "label": "Reference",
          "name": "Reference",
          "show": true
        },
        {
          "group_by": false,
          "label": "Qty",
          "name": "${QUANTITY}",
          "show": true
        },
        {
          "group_by": true,
          "label": "Value",
          "name": "Value",
          "show": true
        },
        {
          "group_by": true,
          "label": "DNP",
          "name": "${DNP}",
          "show": true
        },
        {
          "group_by": true,
          "label": "Exclude from BOM",
          "name": "${EXCLUDE_FROM_BOM}",
          "show": true
        },
        {
          "group_by": true,
          "label": "Exclude from Board",
          "name": "${EXCLUDE_FROM_BOARD}",
          "show": true
        },
        {
          "group_by": true,
          "label": "Footprint",
          "name": "Footprint",
          "show": true
        },
        {
          "group_by": false,
          "label": "Datasheet",
          "name": "Datasheet",
          "show": true
        }
      ],
      "filter_string": "",
      "group_symbols": true,
      "include_excluded_from_bom": true,
      "name": "Default Editing",
      "sort_asc": true,
      "sort_field": "Reference"
    },
    "connection_grid_size": 50.0,
    "drawing": {
      "dashed_lines_dash_length_ratio": 12.0,
      "dashed_lines_gap_length_ratio": 3.0,
      "default_line_thickness": 6.0,
      "default_text_size": 50.0,
      "field_names": [],
      "intersheets_ref_own_page": false,
      "intersheets_ref_prefix": "",
      "intersheets_ref_short": false,
      "intersheets_ref_show": false,
      "intersheets_ref_suffix": "",
      "junction_size_choice": 3,
      "label_size_ratio": 0.25,
      "operating_point_overlay_i_precision": 3,
      "operating_point_overlay_i_range": "~A",
      "operating_point_overlay_v_precision": 3,
      "operating_point_overlay_v_range": "~V",
      "overbar_offset_ratio": 1.23,
      "pin_symbol_size": 0.0,
      "text_offset_ratio": 0.08
    },
    "legacy_lib_dir": "",
    "legacy_lib_list": [],
    "meta": {
      "version": 1
    },
    "net_format_name": "",
    "ngspice": {
      "fix_include_paths": true,
      "fix_passive_vals": false,
      "meta": {
        "version": 0
      },
      "model_mode": 0,
      "workbook_filename": ""
    },
    "page_layout_descr_file": "",
    "plot_directory": "",
    "space_save_all_events": true,
    "spice_adjust_passive_values": false,
    "spice_current_sheet_as_root": false,
    "spice_external_command": "spice \"%I\"",
    "spice_model_current_sheet_as_root": true,
    "spice_save_all_currents": false,
    "spice_save_all_dissipations": false,
    "spice_save_all_voltages": false,
    "subpart_first_id": 65,
    "subpart_id_separator": 0
  },
  "sheets": [
    [
      "",
      "Root"
    ],
    [
      "",
      "EEPROM"
    ],
    [
      "",
      "SODIMM"
    ],
    [
      "",
      "DDR5"
    ]
  ],
  "text_variables": {}
}
